(kicad_pcb
	(version 20260206)
	(generator "pcbnew")
	(generator_version "10.0")
	(general
		(thickness 1.6)
		(legacy_teardrops no)
	)
	(paper "A4")
	(title_block
		(title "03242023_DA0F0TMBIJ0_F0T_Motherboard_J_brd_V01_OCP.brd")
		(comment 1 "Grand Teton / footprints 2659-2664 of 6105")
	)
	(layers
		(0 "F.Cu" signal "TOP")
		(4 "In1.Cu" signal "GND")
		(6 "In2.Cu" signal "IN1")
		(8 "In3.Cu" signal "GND1")
		(10 "In4.Cu" signal "IN2")
		(12 "In5.Cu" signal "GND2")
		(14 "In6.Cu" signal "IN3")
		(16 "In7.Cu" signal "GND3")
		(18 "In8.Cu" signal "VCC")
		(20 "In9.Cu" signal "VCC1")
		(22 "In10.Cu" signal "GND4")
		(24 "In11.Cu" signal "IN4")
		(26 "In12.Cu" signal "GND5")
		(28 "In13.Cu" signal "IN5")
		(30 "In14.Cu" signal "GND6")
		(32 "In15.Cu" signal "IN6")
		(34 "In16.Cu" signal "GND7")
		(2 "B.Cu" signal "BOTTOM")
		(9 "F.Adhes" user "F.Adhesive")
		(11 "B.Adhes" user "B.Adhesive")
		(13 "F.Paste" user "Package Geometry/Pastemask Top")
		(15 "B.Paste" user "Package Geometry/Pastemask Bottom")
		(5 "F.SilkS" user "Ref Des/Silkscreen Top")
		(7 "B.SilkS" user "Ref Des/Silkscreen Bottom")
		(1 "F.Mask" user "Board Geometry/Soldermask Top")
		(3 "B.Mask" user "Board Geometry/Soldermask Bottom")
		(17 "Dwgs.User" user "User.Drawings")
		(19 "Cmts.User" user "User.Comments")
		(21 "Eco1.User" user "User.Eco1")
		(23 "Eco2.User" user "User.Eco2")
		(25 "Edge.Cuts" user "Board Geometry/Outline")
		(27 "Margin" user)
		(31 "F.CrtYd" user "Package Geometry/Place Bound Top")
		(29 "B.CrtYd" user "Package Geometry/Place Bound Bottom")
		(35 "F.Fab" user "Ref Des/Assembly Top")
		(33 "B.Fab" user "Ref Des/Assembly Bottom")
	)
	(footprint ""
		(layer "F.Cu")
		(at 303.600612 -34.937446 -90)
		(property "Reference" "C1177"
			(at 0 0 270)
			(layer "F.SilkS")
			(hide yes)
			(effects
				(font
					(size 1.27 1.27)
				)
			)
		)
		(property "Value" ""
			(at 0 0 270)
			(layer "F.Fab")
			(effects
				(font
					(size 1.27 1.27)
				)
			)
		)
		(duplicate_pad_numbers_are_jumpers no)
		(fp_line
			(start -0.7874 0.4064)
			(end -0.7874 -0.4064)
			(stroke
				(width 0.1524)
				(type default)
			)
			(layer "F.SilkS")
		)
		(fp_line
			(start 0.7874 0.4064)
			(end -0.7874 0.4064)
			(stroke
				(width 0.1524)
				(type default)
			)
			(layer "F.SilkS")
		)
		(fp_line
			(start -0.7874 -0.4064)
			(end 0.7874 -0.4064)
			(stroke
				(width 0.1524)
				(type default)
			)
			(layer "F.SilkS")
		)
		(fp_line
			(start 0.7874 -0.4064)
			(end 0.7874 0.4064)
			(stroke
				(width 0.1524)
				(type default)
			)
			(layer "F.SilkS")
		)
		(fp_line
			(start -0.67945 0.3048)
			(end -0.67945 -0.305054)
			(stroke
				(width 0.1)
				(type default)
			)
			(layer "F.Fab")
		)
		(fp_line
			(start -0.12065 0.3048)
			(end -0.67945 0.3048)
			(stroke
				(width 0.1)
				(type default)
			)
			(layer "F.Fab")
		)
		(fp_line
			(start 0.120396 0.3048)
			(end 0.120396 0.2794)
			(stroke
				(width 0.1)
				(type default)
			)
			(layer "F.Fab")
		)
		(fp_line
			(start 0.67945 0.3048)
			(end 0.120396 0.3048)
			(stroke
				(width 0.1)
				(type default)
			)
			(layer "F.Fab")
		)
		(fp_line
			(start -0.12065 0.2794)
			(end -0.12065 0.3048)
			(stroke
				(width 0.1)
				(type default)
			)
			(layer "F.Fab")
		)
		(fp_line
			(start 0.120396 0.2794)
			(end -0.12065 0.2794)
			(stroke
				(width 0.1)
				(type default)
			)
			(layer "F.Fab")
		)
		(fp_line
			(start -0.12065 -0.2794)
			(end 0.12065 -0.2794)
			(stroke
				(width 0.1)
				(type default)
			)
			(layer "F.Fab")
		)
		(fp_line
			(start 0.12065 -0.2794)
			(end 0.12065 -0.3048)
			(stroke
				(width 0.1)
				(type default)
			)
			(layer "F.Fab")
		)
		(fp_line
			(start 0.12065 -0.3048)
			(end 0.67945 -0.3048)
			(stroke
				(width 0.1)
				(type default)
			)
			(layer "F.Fab")
		)
		(fp_line
			(start 0.67945 -0.3048)
			(end 0.67945 0.3048)
			(stroke
				(width 0.1)
				(type default)
			)
			(layer "F.Fab")
		)
		(fp_line
			(start -0.67945 -0.305054)
			(end -0.12065 -0.305054)
			(stroke
				(width 0.1)
				(type default)
			)
			(layer "F.Fab")
		)
		(fp_line
			(start -0.12065 -0.305054)
			(end -0.12065 -0.2794)
			(stroke
				(width 0.1)
				(type default)
			)
			(layer "F.Fab")
		)
		(pad "1" smd circle
			(at -0.40005 0 270)
			(size 0 0)
			(layers "F.Cu" "F.Mask" "F.Paste")
			(net "RST_RTCRST_N")
		)
		(pad "2" smd circle
			(at 0.40005 0 270)
			(size 0 0)
			(layers "F.Cu" "F.Mask" "F.Paste")
			(net "GND")
		)
	)
	(footprint ""
		(layer "F.Cu")
		(at 164.64788 -122.646948 180)
		(property "Reference" "R1413"
			(at 0 0 180)
			(layer "F.SilkS")
			(hide yes)
			(effects
				(font
					(size 1.27 1.27)
				)
			)
		)
		(property "Value" ""
			(at 0 0 180)
			(layer "F.Fab")
			(effects
				(font
					(size 1.27 1.27)
				)
			)
		)
		(duplicate_pad_numbers_are_jumpers no)
		(fp_line
			(start 0.7874 0.4064)
			(end -0.7874 0.4064)
			(stroke
				(width 0.1524)
				(type default)
			)
			(layer "F.SilkS")
		)
		(fp_line
			(start 0.7874 -0.4064)
			(end 0.7874 0.4064)
			(stroke
				(width 0.1524)
				(type default)
			)
			(layer "F.SilkS")
		)
		(fp_line
			(start -0.7874 0.4064)
			(end -0.7874 -0.4064)
			(stroke
				(width 0.1524)
				(type default)
			)
			(layer "F.SilkS")
		)
		(fp_line
			(start -0.7874 -0.4064)
			(end 0.7874 -0.4064)
			(stroke
				(width 0.1524)
				(type default)
			)
			(layer "F.SilkS")
		)
		(fp_line
			(start 0.67945 0.3048)
			(end 0.120396 0.3048)
			(stroke
				(width 0.1)
				(type default)
			)
			(layer "F.Fab")
		)
		(fp_line
			(start 0.67945 -0.3048)
			(end 0.67945 0.3048)
			(stroke
				(width 0.1)
				(type default)
			)
			(layer "F.Fab")
		)
		(fp_line
			(start 0.12065 -0.2794)
			(end 0.12065 -0.3048)
			(stroke
				(width 0.1)
				(type default)
			)
			(layer "F.Fab")
		)
		(fp_line
			(start 0.12065 -0.3048)
			(end 0.67945 -0.3048)
			(stroke
				(width 0.1)
				(type default)
			)
			(layer "F.Fab")
		)
		(fp_line
			(start 0.120396 0.3048)
			(end 0.120396 0.2794)
			(stroke
				(width 0.1)
				(type default)
			)
			(layer "F.Fab")
		)
		(fp_line
			(start 0.120396 0.2794)
			(end -0.12065 0.2794)
			(stroke
				(width 0.1)
				(type default)
			)
			(layer "F.Fab")
		)
		(fp_line
			(start -0.12065 0.3048)
			(end -0.67945 0.3048)
			(stroke
				(width 0.1)
				(type default)
			)
			(layer "F.Fab")
		)
		(fp_line
			(start -0.12065 0.2794)
			(end -0.12065 0.3048)
			(stroke
				(width 0.1)
				(type default)
			)
			(layer "F.Fab")
		)
		(fp_line
			(start -0.12065 -0.2794)
			(end 0.12065 -0.2794)
			(stroke
				(width 0.1)
				(type default)
			)
			(layer "F.Fab")
		)
		(fp_line
			(start -0.12065 -0.305054)
			(end -0.12065 -0.2794)
			(stroke
				(width 0.1)
				(type default)
			)
			(layer "F.Fab")
		)
		(fp_line
			(start -0.67945 0.3048)
			(end -0.67945 -0.305054)
			(stroke
				(width 0.1)
				(type default)
			)
			(layer "F.Fab")
		)
		(fp_line
			(start -0.67945 -0.305054)
			(end -0.12065 -0.305054)
			(stroke
				(width 0.1)
				(type default)
			)
			(layer "F.Fab")
		)
		(pad "1" smd circle
			(at -0.40005 0 180)
			(size 0 0)
			(layers "F.Cu" "F.Mask" "F.Paste")
			(net "FM_PVCCD_HV_CPU0_EN")
		)
		(pad "2" smd circle
			(at 0.40005 0 180)
			(size 0 0)
			(layers "F.Cu" "F.Mask" "F.Paste")
			(net "GND")
		)
	)
	(footprint ""
		(layer "F.Cu")
		(at 197.41388 -113.502948 90)
		(property "Reference" "R1099"
			(at 0 0 90)
			(layer "F.SilkS")
			(hide yes)
			(effects
				(font
					(size 1.27 1.27)
				)
			)
		)
		(property "Value" ""
			(at 0 0 90)
			(layer "F.Fab")
			(effects
				(font
					(size 1.27 1.27)
				)
			)
		)
		(duplicate_pad_numbers_are_jumpers no)
		(fp_line
			(start 0.7874 -0.4064)
			(end 0.7874 0.4064)
			(stroke
				(width 0.1524)
				(type default)
			)
			(layer "F.SilkS")
		)
		(fp_line
			(start -0.7874 -0.4064)
			(end 0.7874 -0.4064)
			(stroke
				(width 0.1524)
				(type default)
			)
			(layer "F.SilkS")
		)
		(fp_line
			(start 0.7874 0.4064)
			(end -0.7874 0.4064)
			(stroke
				(width 0.1524)
				(type default)
			)
			(layer "F.SilkS")
		)
		(fp_line
			(start -0.7874 0.4064)
			(end -0.7874 -0.4064)
			(stroke
				(width 0.1524)
				(type default)
			)
			(layer "F.SilkS")
		)
		(fp_line
			(start -0.12065 -0.305054)
			(end -0.12065 -0.2794)
			(stroke
				(width 0.1)
				(type default)
			)
			(layer "F.Fab")
		)
		(fp_line
			(start -0.67945 -0.305054)
			(end -0.12065 -0.305054)
			(stroke
				(width 0.1)
				(type default)
			)
			(layer "F.Fab")
		)
		(fp_line
			(start 0.67945 -0.3048)
			(end 0.67945 0.3048)
			(stroke
				(width 0.1)
				(type default)
			)
			(layer "F.Fab")
		)
		(fp_line
			(start 0.12065 -0.3048)
			(end 0.67945 -0.3048)
			(stroke
				(width 0.1)
				(type default)
			)
			(layer "F.Fab")
		)
		(fp_line
			(start 0.12065 -0.2794)
			(end 0.12065 -0.3048)
			(stroke
				(width 0.1)
				(type default)
			)
			(layer "F.Fab")
		)
		(fp_line
			(start -0.12065 -0.2794)
			(end 0.12065 -0.2794)
			(stroke
				(width 0.1)
				(type default)
			)
			(layer "F.Fab")
		)
		(fp_line
			(start 0.120396 0.2794)
			(end -0.12065 0.2794)
			(stroke
				(width 0.1)
				(type default)
			)
			(layer "F.Fab")
		)
		(fp_line
			(start -0.12065 0.2794)
			(end -0.12065 0.3048)
			(stroke
				(width 0.1)
				(type default)
			)
			(layer "F.Fab")
		)
		(fp_line
			(start 0.67945 0.3048)
			(end 0.120396 0.3048)
			(stroke
				(width 0.1)
				(type default)
			)
			(layer "F.Fab")
		)
		(fp_line
			(start 0.120396 0.3048)
			(end 0.120396 0.2794)
			(stroke
				(width 0.1)
				(type default)
			)
			(layer "F.Fab")
		)
		(fp_line
			(start -0.12065 0.3048)
			(end -0.67945 0.3048)
			(stroke
				(width 0.1)
				(type default)
			)
			(layer "F.Fab")
		)
		(fp_line
			(start -0.67945 0.3048)
			(end -0.67945 -0.305054)
			(stroke
				(width 0.1)
				(type default)
			)
			(layer "F.Fab")
		)
		(pad "1" smd circle
			(at -0.40005 0 90)
			(size 0 0)
			(layers "F.Cu" "F.Mask" "F.Paste")
			(net "P3V3_AUX")
		)
		(pad "2" smd circle
			(at 0.40005 0 90)
			(size 0 0)
			(layers "F.Cu" "F.Mask" "F.Paste")
			(net "PU_CLK25M_OSC_FPGA_EN")
		)
	)
	(footprint ""
		(layer "F.Cu")
		(at 103.40975 -360.934762 90)
		(property "Reference" "C2859"
			(at 0 0 90)
			(layer "F.SilkS")
			(hide yes)
			(effects
				(font
					(size 1.27 1.27)
				)
			)
		)
		(property "Value" ""
			(at 0 0 90)
			(layer "F.Fab")
			(effects
				(font
					(size 1.27 1.27)
				)
			)
		)
		(duplicate_pad_numbers_are_jumpers no)
		(fp_line
			(start 0.7874 -0.4064)
			(end 0.7874 0.4064)
			(stroke
				(width 0.1524)
				(type default)
			)
			(layer "F.SilkS")
		)
		(fp_line
			(start -0.7874 -0.4064)
			(end 0.7874 -0.4064)
			(stroke
				(width 0.1524)
				(type default)
			)
			(layer "F.SilkS")
		)
		(fp_line
			(start 0.7874 0.4064)
			(end -0.7874 0.4064)
			(stroke
				(width 0.1524)
				(type default)
			)
			(layer "F.SilkS")
		)
		(fp_line
			(start -0.7874 0.4064)
			(end -0.7874 -0.4064)
			(stroke
				(width 0.1524)
				(type default)
			)
			(layer "F.SilkS")
		)
		(fp_line
			(start -0.12065 -0.305054)
			(end -0.12065 -0.2794)
			(stroke
				(width 0.1)
				(type default)
			)
			(layer "F.Fab")
		)
		(fp_line
			(start -0.67945 -0.305054)
			(end -0.12065 -0.305054)
			(stroke
				(width 0.1)
				(type default)
			)
			(layer "F.Fab")
		)
		(fp_line
			(start 0.67945 -0.3048)
			(end 0.67945 0.3048)
			(stroke
				(width 0.1)
				(type default)
			)
			(layer "F.Fab")
		)
		(fp_line
			(start 0.12065 -0.3048)
			(end 0.67945 -0.3048)
			(stroke
				(width 0.1)
				(type default)
			)
			(layer "F.Fab")
		)
		(fp_line
			(start 0.12065 -0.2794)
			(end 0.12065 -0.3048)
			(stroke
				(width 0.1)
				(type default)
			)
			(layer "F.Fab")
		)
		(fp_line
			(start -0.12065 -0.2794)
			(end 0.12065 -0.2794)
			(stroke
				(width 0.1)
				(type default)
			)
			(layer "F.Fab")
		)
		(fp_line
			(start 0.120396 0.2794)
			(end -0.12065 0.2794)
			(stroke
				(width 0.1)
				(type default)
			)
			(layer "F.Fab")
		)
		(fp_line
			(start -0.12065 0.2794)
			(end -0.12065 0.3048)
			(stroke
				(width 0.1)
				(type default)
			)
			(layer "F.Fab")
		)
		(fp_line
			(start 0.67945 0.3048)
			(end 0.120396 0.3048)
			(stroke
				(width 0.1)
				(type default)
			)
			(layer "F.Fab")
		)
		(fp_line
			(start 0.120396 0.3048)
			(end 0.120396 0.2794)
			(stroke
				(width 0.1)
				(type default)
			)
			(layer "F.Fab")
		)
		(fp_line
			(start -0.12065 0.3048)
			(end -0.67945 0.3048)
			(stroke
				(width 0.1)
				(type default)
			)
			(layer "F.Fab")
		)
		(fp_line
			(start -0.67945 0.3048)
			(end -0.67945 -0.305054)
			(stroke
				(width 0.1)
				(type default)
			)
			(layer "F.Fab")
		)
		(pad "1" smd circle
			(at -0.40005 0 90)
			(size 0 0)
			(layers "F.Cu" "F.Mask" "F.Paste")
			(net "PWRGD_PVCCIN_CPU1_R")
		)
		(pad "2" smd circle
			(at 0.40005 0 90)
			(size 0 0)
			(layers "F.Cu" "F.Mask" "F.Paste")
			(net "GND")
		)
	)
	(footprint ""
		(layer "F.Cu")
		(at 119.02948 -357.114348 90)
		(property "Reference" "PR2381"
			(at 0 0 90)
			(layer "F.SilkS")
			(hide yes)
			(effects
				(font
					(size 1.27 1.27)
				)
			)
		)
		(property "Value" ""
			(at 0 0 90)
			(layer "F.Fab")
			(effects
				(font
					(size 1.27 1.27)
				)
			)
		)
		(duplicate_pad_numbers_are_jumpers no)
		(fp_line
			(start 0.7874 -0.4064)
			(end 0.7874 0.4064)
			(stroke
				(width 0.1524)
				(type default)
			)
			(layer "F.SilkS")
		)
		(fp_line
			(start -0.7874 -0.4064)
			(end 0.7874 -0.4064)
			(stroke
				(width 0.1524)
				(type default)
			)
			(layer "F.SilkS")
		)
		(fp_line
			(start 0.7874 0.4064)
			(end -0.7874 0.4064)
			(stroke
				(width 0.1524)
				(type default)
			)
			(layer "F.SilkS")
		)
		(fp_line
			(start -0.7874 0.4064)
			(end -0.7874 -0.4064)
			(stroke
				(width 0.1524)
				(type default)
			)
			(layer "F.SilkS")
		)
		(fp_line
			(start -0.12065 -0.305054)
			(end -0.12065 -0.2794)
			(stroke
				(width 0.1)
				(type default)
			)
			(layer "F.Fab")
		)
		(fp_line
			(start -0.67945 -0.305054)
			(end -0.12065 -0.305054)
			(stroke
				(width 0.1)
				(type default)
			)
			(layer "F.Fab")
		)
		(fp_line
			(start 0.67945 -0.3048)
			(end 0.67945 0.3048)
			(stroke
				(width 0.1)
				(type default)
			)
			(layer "F.Fab")
		)
		(fp_line
			(start 0.12065 -0.3048)
			(end 0.67945 -0.3048)
			(stroke
				(width 0.1)
				(type default)
			)
			(layer "F.Fab")
		)
		(fp_line
			(start 0.12065 -0.2794)
			(end 0.12065 -0.3048)
			(stroke
				(width 0.1)
				(type default)
			)
			(layer "F.Fab")
		)
		(fp_line
			(start -0.12065 -0.2794)
			(end 0.12065 -0.2794)
			(stroke
				(width 0.1)
				(type default)
			)
			(layer "F.Fab")
		)
		(fp_line
			(start 0.120396 0.2794)
			(end -0.12065 0.2794)
			(stroke
				(width 0.1)
				(type default)
			)
			(layer "F.Fab")
		)
		(fp_line
			(start -0.12065 0.2794)
			(end -0.12065 0.3048)
			(stroke
				(width 0.1)
				(type default)
			)
			(layer "F.Fab")
		)
		(fp_line
			(start 0.67945 0.3048)
			(end 0.120396 0.3048)
			(stroke
				(width 0.1)
				(type default)
			)
			(layer "F.Fab")
		)
		(fp_line
			(start 0.120396 0.3048)
			(end 0.120396 0.2794)
			(stroke
				(width 0.1)
				(type default)
			)
			(layer "F.Fab")
		)
		(fp_line
			(start -0.12065 0.3048)
			(end -0.67945 0.3048)
			(stroke
				(width 0.1)
				(type default)
			)
			(layer "F.Fab")
		)
		(fp_line
			(start -0.67945 0.3048)
			(end -0.67945 -0.305054)
			(stroke
				(width 0.1)
				(type default)
			)
			(layer "F.Fab")
		)
		(pad "1" smd circle
			(at -0.40005 0 90)
			(size 0 0)
			(layers "F.Cu" "F.Mask" "F.Paste")
			(net "PVPP_HBM_CPU1_FB")
		)
		(pad "2" smd circle
			(at 0.40005 0 90)
			(size 0 0)
			(layers "F.Cu" "F.Mask" "F.Paste")
			(net "FM_HBM_VPP_SEL_CPU1_D")
		)
	)
	(footprint ""
		(layer "F.Cu")
		(at 22.13356 -163.719256)
		(property "Reference" "R2580"
			(at 0 0 0)
			(layer "F.SilkS")
			(hide yes)
			(effects
				(font
					(size 1.27 1.27)
				)
			)
		)
		(property "Value" ""
			(at 0 0 0)
			(layer "F.Fab")
			(effects
				(font
					(size 1.27 1.27)
				)
			)
		)
		(duplicate_pad_numbers_are_jumpers no)
		(fp_line
			(start -0.7874 -0.4064)
			(end 0.7874 -0.4064)
			(stroke
				(width 0.1524)
				(type default)
			)
			(layer "F.SilkS")
		)
		(fp_line
			(start -0.7874 0.4064)
			(end -0.7874 -0.4064)
			(stroke
				(width 0.1524)
				(type default)
			)
			(layer "F.SilkS")
		)
		(fp_line
			(start 0.7874 -0.4064)
			(end 0.7874 0.4064)
			(stroke
				(width 0.1524)
				(type default)
			)
			(layer "F.SilkS")
		)
		(fp_line
			(start 0.7874 0.4064)
			(end -0.7874 0.4064)
			(stroke
				(width 0.1524)
				(type default)
			)
			(layer "F.SilkS")
		)
		(fp_line
			(start -0.67945 -0.305054)
			(end -0.12065 -0.305054)
			(stroke
				(width 0.1)
				(type default)
			)
			(layer "F.Fab")
		)
		(fp_line
			(start -0.67945 0.3048)
			(end -0.67945 -0.305054)
			(stroke
				(width 0.1)
				(type default)
			)
			(layer "F.Fab")
		)
		(fp_line
			(start -0.12065 -0.305054)
			(end -0.12065 -0.2794)
			(stroke
				(width 0.1)
				(type default)
			)
			(layer "F.Fab")
		)
		(fp_line
			(start -0.12065 -0.2794)
			(end 0.12065 -0.2794)
			(stroke
				(width 0.1)
				(type default)
			)
			(layer "F.Fab")
		)
		(fp_line
			(start -0.12065 0.2794)
			(end -0.12065 0.3048)
			(stroke
				(width 0.1)
				(type default)
			)
			(layer "F.Fab")
		)
		(fp_line
			(start -0.12065 0.3048)
			(end -0.67945 0.3048)
			(stroke
				(width 0.1)
				(type default)
			)
			(layer "F.Fab")
		)
		(fp_line
			(start 0.120396 0.2794)
			(end -0.12065 0.2794)
			(stroke
				(width 0.1)
				(type default)
			)
			(layer "F.Fab")
		)
		(fp_line
			(start 0.120396 0.3048)
			(end 0.120396 0.2794)
			(stroke
				(width 0.1)
				(type default)
			)
			(layer "F.Fab")
		)
		(fp_line
			(start 0.12065 -0.3048)
			(end 0.67945 -0.3048)
			(stroke
				(width 0.1)
				(type default)
			)
			(layer "F.Fab")
		)
		(fp_line
			(start 0.12065 -0.2794)
			(end 0.12065 -0.3048)
			(stroke
				(width 0.1)
				(type default)
			)
			(layer "F.Fab")
		)
		(fp_line
			(start 0.67945 -0.3048)
			(end 0.67945 0.3048)
			(stroke
				(width 0.1)
				(type default)
			)
			(layer "F.Fab")
		)
		(fp_line
			(start 0.67945 0.3048)
			(end 0.120396 0.3048)
			(stroke
				(width 0.1)
				(type default)
			)
			(layer "F.Fab")
		)
		(pad "1" smd circle
			(at -0.40005 0)
			(size 0 0)
			(layers "F.Cu" "F.Mask" "F.Paste")
			(net "SVID_ALERT1_CPU1_R_N")
		)
		(pad "2" smd circle
			(at 0.40005 0)
			(size 0 0)
			(layers "F.Cu" "F.Mask" "F.Paste")
			(net "SVID_ALERT_PVCCD_HV_CPU1_R")
		)
	)
)
